(kicad_pcb
	(version 20260206)
	(generator "pcbnew")
	(generator_version "10.0")
	(general
		(thickness 1.6)
		(legacy_teardrops no)
	)
	(paper "A4")
	(title_block
		(title "peb — Lightning_PEB_BRD.brd")
		(comment 1 "Lightning (Wiwynn / Facebook NVMe JBOF) / footprints 1094-1101 of 2563")
	)
	(layers
		(0 "F.Cu" signal "TOP")
		(4 "In1.Cu" signal "L2GND")
		(6 "In2.Cu" signal "L3")
		(8 "In3.Cu" signal "L4VCC")
		(10 "In4.Cu" signal "L5VCC")
		(12 "In5.Cu" signal "L6")
		(14 "In6.Cu" signal "L7GND")
		(2 "B.Cu" signal "BOTTOM")
		(9 "F.Adhes" user "F.Adhesive")
		(11 "B.Adhes" user "B.Adhesive")
		(13 "F.Paste" user "Package Geometry/Pastemask Top")
		(15 "B.Paste" user "Package Geometry/Pastemask Bottom")
		(5 "F.SilkS" user "Ref Des/Silkscreen Top")
		(7 "B.SilkS" user "Ref Des/Silkscreen Bottom")
		(1 "F.Mask" user "Board Geometry/Soldermask Top")
		(3 "B.Mask" user "Board Geometry/Soldermask Bottom")
		(17 "Dwgs.User" user "User.Drawings")
		(19 "Cmts.User" user "User.Comments")
		(21 "Eco1.User" user "User.Eco1")
		(23 "Eco2.User" user "User.Eco2")
		(25 "Edge.Cuts" user "Board Geometry/Outline")
		(27 "Margin" user)
		(31 "F.CrtYd" user "Package Geometry/Place Bound Top")
		(29 "B.CrtYd" user "Package Geometry/Place Bound Bottom")
		(35 "F.Fab" user "Ref Des/Assembly Top")
		(33 "B.Fab" user "Ref Des/Assembly Bottom")
	)
	(footprint ""
		(layer "F.Cu")
		(at 315.722 -33.528)
		(property "Reference" "C45"
			(at 0 0 0)
			(layer "F.SilkS")
			(hide yes)
			(effects
				(font
					(size 1.27 1.27)
				)
			)
		)
		(property "Value" "SCD22U10V2KX-1GP"
			(at 1.1811 -2.7051 0)
			(unlocked yes)
			(layer "F.Fab")
			(hide yes)
			(effects
				(font
					(size 1.016 1.016)
					(thickness 0.1524)
				)
			)
		)
		(property "Device Type" "C402H22"
			(at 1.1811 -4.2291 0)
			(unlocked yes)
			(layer "F.Fab")
			(hide yes)
			(effects
				(font
					(size 1.016 1.016)
					(thickness 0.1524)
				)
			)
		)
		(duplicate_pad_numbers_are_jumpers no)
		(fp_rect
			(start -0.4318 0.9525)
			(end 0.4318 -0.9525)
			(stroke
				(width 0)
				(type default)
			)
			(fill no)
			(layer "F.CrtYd")
		)
		(fp_rect
			(start -0.4318 0.9525)
			(end 0.4318 -0.9525)
			(stroke
				(width 0)
				(type default)
			)
			(fill no)
			(layer "F.Fab")
		)
		(pad "1" smd custom
			(at 0 -0.4445)
			(size 0.1524 0.1524)
			(layers "F.Cu" "F.Mask" "F.Paste")
			(net "PCIE_TX_CAP_N11")
			(options
				(clearance outline)
				(anchor circle)
			)
			(primitives
				(gr_poly
					(pts
						(arc
							(start 0.3048 -0.2032)
							(mid 0.275042 -0.275042)
							(end 0.2032 -0.3048)
						)
						(arc
							(start -0.2032 -0.3048)
							(mid -0.275042 -0.275042)
							(end -0.3048 -0.2032)
						)
						(arc
							(start -0.3048 0.2032)
							(mid -0.275042 0.275042)
							(end -0.2032 0.3048)
						)
						(arc
							(start 0.2032 0.3048)
							(mid 0.275042 0.275042)
							(end 0.3048 0.2032)
						)
					)
					(width 0)
					(fill yes)
				)
			)
		)
		(pad "2" smd custom
			(at 0 0.4445)
			(size 0.1524 0.1524)
			(layers "F.Cu" "F.Mask" "F.Paste")
			(net "PCIE_TX_N11")
			(options
				(clearance outline)
				(anchor circle)
			)
			(primitives
				(gr_poly
					(pts
						(arc
							(start 0.3048 -0.2032)
							(mid 0.275042 -0.275042)
							(end 0.2032 -0.3048)
						)
						(arc
							(start -0.2032 -0.3048)
							(mid -0.275042 -0.275042)
							(end -0.3048 -0.2032)
						)
						(arc
							(start -0.3048 0.2032)
							(mid -0.275042 0.275042)
							(end -0.2032 0.3048)
						)
						(arc
							(start 0.2032 0.3048)
							(mid 0.275042 0.275042)
							(end 0.3048 0.2032)
						)
					)
					(width 0)
					(fill yes)
				)
			)
		)
	)
	(footprint ""
		(layer "F.Cu")
		(at 34.429954 -164.702744 90)
		(property "Reference" "R231"
			(at 0 0 90)
			(layer "F.SilkS")
			(hide yes)
			(effects
				(font
					(size 1.27 1.27)
				)
			)
		)
		(property "Value" "1KR2F-3-GP"
			(at 0.064008 -3.993896 90)
			(unlocked yes)
			(layer "F.Fab")
			(hide yes)
			(effects
				(font
					(size 1.016 1.016)
					(thickness 0.1524)
				)
			)
		)
		(property "Device Type" "R402H16"
			(at 0.064008 -5.517896 90)
			(unlocked yes)
			(layer "F.Fab")
			(hide yes)
			(effects
				(font
					(size 1.016 1.016)
					(thickness 0.1524)
				)
			)
		)
		(duplicate_pad_numbers_are_jumpers no)
		(fp_line
			(start 0.508 -0.9398)
			(end -0.508 -0.9398)
			(stroke
				(width 0.1524)
				(type default)
			)
			(layer "F.SilkS")
		)
		(fp_line
			(start -0.508 -0.9398)
			(end -0.508 0.9398)
			(stroke
				(width 0.1524)
				(type default)
			)
			(layer "F.SilkS")
		)
		(fp_rect
			(start -0.508 0.9398)
			(end 0.508 -0.9398)
			(stroke
				(width 0)
				(type default)
			)
			(fill no)
			(layer "F.CrtYd")
		)
		(fp_rect
			(start -0.508 0.9398)
			(end 0.508 -0.9398)
			(stroke
				(width 0)
				(type default)
			)
			(fill no)
			(layer "F.Fab")
		)
		(pad "1" smd custom
			(at 0 -0.4445 90)
			(size 0.1397 0.1397)
			(layers "F.Cu" "F.Mask" "F.Paste")
			(net "P1V53_STBY")
			(options
				(clearance outline)
				(anchor circle)
			)
			(primitives
				(gr_poly
					(pts
						(arc
							(start -0.1778 -0.2794)
							(mid -0.249642 -0.249642)
							(end -0.2794 -0.1778)
						)
						(arc
							(start -0.2794 0.1778)
							(mid -0.249642 0.249642)
							(end -0.1778 0.2794)
						)
						(arc
							(start 0.1778 0.2794)
							(mid 0.249642 0.249642)
							(end 0.2794 0.1778)
						)
						(arc
							(start 0.2794 -0.1778)
							(mid 0.249642 -0.249642)
							(end 0.1778 -0.2794)
						)
					)
					(width 0)
					(fill yes)
				)
			)
		)
		(pad "2" smd custom
			(at 0 0.4445 90)
			(size 0.1397 0.1397)
			(layers "F.Cu" "F.Mask" "F.Paste")
			(net "DDR_VREF")
			(options
				(clearance outline)
				(anchor circle)
			)
			(primitives
				(gr_poly
					(pts
						(arc
							(start -0.1778 -0.2794)
							(mid -0.249642 -0.249642)
							(end -0.2794 -0.1778)
						)
						(arc
							(start -0.2794 0.1778)
							(mid -0.249642 0.249642)
							(end -0.1778 0.2794)
						)
						(arc
							(start 0.1778 0.2794)
							(mid 0.249642 0.249642)
							(end 0.2794 0.1778)
						)
						(arc
							(start 0.2794 -0.1778)
							(mid 0.249642 -0.249642)
							(end 0.1778 -0.2794)
						)
					)
					(width 0)
					(fill yes)
				)
			)
		)
	)
	(footprint ""
		(layer "F.Cu")
		(at 265.684 -26.289 180)
		(property "Reference" "R764"
			(at 0 0 180)
			(layer "F.SilkS")
			(hide yes)
			(effects
				(font
					(size 1.27 1.27)
				)
			)
		)
		(property "Value" "1KR2F-3-GP"
			(at 0.064008 -3.993896 180)
			(unlocked yes)
			(layer "F.Fab")
			(hide yes)
			(effects
				(font
					(size 1.016 1.016)
					(thickness 0.1524)
				)
			)
		)
		(property "Device Type" "R402H16"
			(at 0.064008 -5.517896 180)
			(unlocked yes)
			(layer "F.Fab")
			(hide yes)
			(effects
				(font
					(size 1.016 1.016)
					(thickness 0.1524)
				)
			)
		)
		(duplicate_pad_numbers_are_jumpers no)
		(fp_line
			(start 0.508 -0.9398)
			(end -0.508 -0.9398)
			(stroke
				(width 0.1524)
				(type default)
			)
			(layer "F.SilkS")
		)
		(fp_line
			(start -0.508 -0.9398)
			(end -0.508 0.9398)
			(stroke
				(width 0.1524)
				(type default)
			)
			(layer "F.SilkS")
		)
		(fp_rect
			(start -0.508 0.9398)
			(end 0.508 -0.9398)
			(stroke
				(width 0)
				(type default)
			)
			(fill no)
			(layer "F.CrtYd")
		)
		(fp_rect
			(start -0.508 0.9398)
			(end 0.508 -0.9398)
			(stroke
				(width 0)
				(type default)
			)
			(fill no)
			(layer "F.Fab")
		)
		(pad "1" smd custom
			(at 0 -0.4445 180)
			(size 0.1397 0.1397)
			(layers "F.Cu" "F.Mask" "F.Paste")
			(net "P3V3_GPIO")
			(options
				(clearance outline)
				(anchor circle)
			)
			(primitives
				(gr_poly
					(pts
						(arc
							(start -0.1778 -0.2794)
							(mid -0.249642 -0.249642)
							(end -0.2794 -0.1778)
						)
						(arc
							(start -0.2794 0.1778)
							(mid -0.249642 0.249642)
							(end -0.1778 0.2794)
						)
						(arc
							(start 0.1778 0.2794)
							(mid 0.249642 0.249642)
							(end 0.2794 0.1778)
						)
						(arc
							(start 0.2794 -0.1778)
							(mid 0.249642 -0.249642)
							(end 0.1778 -0.2794)
						)
					)
					(width 0)
					(fill yes)
				)
			)
		)
		(pad "2" smd custom
			(at 0 0.4445 180)
			(size 0.1397 0.1397)
			(layers "F.Cu" "F.Mask" "F.Paste")
			(net "TWI_SDA1")
			(options
				(clearance outline)
				(anchor circle)
			)
			(primitives
				(gr_poly
					(pts
						(arc
							(start -0.1778 -0.2794)
							(mid -0.249642 -0.249642)
							(end -0.2794 -0.1778)
						)
						(arc
							(start -0.2794 0.1778)
							(mid -0.249642 0.249642)
							(end -0.1778 0.2794)
						)
						(arc
							(start 0.1778 0.2794)
							(mid 0.249642 0.249642)
							(end 0.2794 0.1778)
						)
						(arc
							(start 0.2794 -0.1778)
							(mid 0.249642 -0.249642)
							(end 0.1778 -0.2794)
						)
					)
					(width 0)
					(fill yes)
				)
			)
		)
	)
	(footprint ""
		(layer "F.Cu")
		(at 55.88 -123.5964 90)
		(property "Reference" "R279"
			(at 0 0 90)
			(layer "F.SilkS")
			(hide yes)
			(effects
				(font
					(size 1.27 1.27)
				)
			)
		)
		(property "Value" "0R2J-2-GP"
			(at 0.064008 -3.993896 90)
			(unlocked yes)
			(layer "F.Fab")
			(hide yes)
			(effects
				(font
					(size 1.016 1.016)
					(thickness 0.1524)
				)
			)
		)
		(property "Device Type" "R402H16"
			(at 0.064008 -5.517896 90)
			(unlocked yes)
			(layer "F.Fab")
			(hide yes)
			(effects
				(font
					(size 1.016 1.016)
					(thickness 0.1524)
				)
			)
		)
		(duplicate_pad_numbers_are_jumpers no)
		(fp_line
			(start 0.508 -0.9398)
			(end -0.508 -0.9398)
			(stroke
				(width 0.1524)
				(type default)
			)
			(layer "F.SilkS")
		)
		(fp_line
			(start -0.508 -0.9398)
			(end -0.508 0.9398)
			(stroke
				(width 0.1524)
				(type default)
			)
			(layer "F.SilkS")
		)
		(fp_rect
			(start -0.508 0.9398)
			(end 0.508 -0.9398)
			(stroke
				(width 0)
				(type default)
			)
			(fill no)
			(layer "F.CrtYd")
		)
		(fp_rect
			(start -0.508 0.9398)
			(end 0.508 -0.9398)
			(stroke
				(width 0)
				(type default)
			)
			(fill no)
			(layer "F.Fab")
		)
		(pad "1" smd custom
			(at 0 -0.4445 90)
			(size 0.1397 0.1397)
			(layers "F.Cu" "F.Mask" "F.Paste")
			(net "BMC_RXD5_R")
			(options
				(clearance outline)
				(anchor circle)
			)
			(primitives
				(gr_poly
					(pts
						(arc
							(start -0.1778 -0.2794)
							(mid -0.249642 -0.249642)
							(end -0.2794 -0.1778)
						)
						(arc
							(start -0.2794 0.1778)
							(mid -0.249642 0.249642)
							(end -0.1778 0.2794)
						)
						(arc
							(start 0.1778 0.2794)
							(mid 0.249642 0.249642)
							(end 0.2794 0.1778)
						)
						(arc
							(start 0.2794 -0.1778)
							(mid 0.249642 -0.249642)
							(end 0.1778 -0.2794)
						)
					)
					(width 0)
					(fill yes)
				)
			)
		)
		(pad "2" smd custom
			(at 0 0.4445 90)
			(size 0.1397 0.1397)
			(layers "F.Cu" "F.Mask" "F.Paste")
			(net "BMC_RXD5")
			(options
				(clearance outline)
				(anchor circle)
			)
			(primitives
				(gr_poly
					(pts
						(arc
							(start -0.1778 -0.2794)
							(mid -0.249642 -0.249642)
							(end -0.2794 -0.1778)
						)
						(arc
							(start -0.2794 0.1778)
							(mid -0.249642 0.249642)
							(end -0.1778 0.2794)
						)
						(arc
							(start 0.1778 0.2794)
							(mid 0.249642 0.249642)
							(end 0.2794 0.1778)
						)
						(arc
							(start 0.2794 -0.1778)
							(mid 0.249642 -0.249642)
							(end 0.1778 -0.2794)
						)
					)
					(width 0)
					(fill yes)
				)
			)
		)
	)
	(footprint ""
		(layer "F.Cu")
		(at 57.15 -133.985 180)
		(property "Reference" "R5767"
			(at 0 0 180)
			(layer "F.SilkS")
			(hide yes)
			(effects
				(font
					(size 1.27 1.27)
				)
			)
		)
		(property "Value" "1KR2F-3-GP"
			(at 0.064008 -3.993896 180)
			(unlocked yes)
			(layer "F.Fab")
			(hide yes)
			(effects
				(font
					(size 1.016 1.016)
					(thickness 0.1524)
				)
			)
		)
		(property "Device Type" "R402H16"
			(at 0.064008 -5.517896 180)
			(unlocked yes)
			(layer "F.Fab")
			(hide yes)
			(effects
				(font
					(size 1.016 1.016)
					(thickness 0.1524)
				)
			)
		)
		(duplicate_pad_numbers_are_jumpers no)
		(fp_line
			(start 0.508 -0.9398)
			(end -0.508 -0.9398)
			(stroke
				(width 0.1524)
				(type default)
			)
			(layer "F.SilkS")
		)
		(fp_line
			(start -0.508 -0.9398)
			(end -0.508 0.9398)
			(stroke
				(width 0.1524)
				(type default)
			)
			(layer "F.SilkS")
		)
		(fp_rect
			(start -0.508 0.9398)
			(end 0.508 -0.9398)
			(stroke
				(width 0)
				(type default)
			)
			(fill no)
			(layer "F.CrtYd")
		)
		(fp_rect
			(start -0.508 0.9398)
			(end 0.508 -0.9398)
			(stroke
				(width 0)
				(type default)
			)
			(fill no)
			(layer "F.Fab")
		)
		(pad "1" smd custom
			(at 0 -0.4445 180)
			(size 0.1397 0.1397)
			(layers "F.Cu" "F.Mask" "F.Paste")
			(net "ADC_P1V8_STBY")
			(options
				(clearance outline)
				(anchor circle)
			)
			(primitives
				(gr_poly
					(pts
						(arc
							(start -0.1778 -0.2794)
							(mid -0.249642 -0.249642)
							(end -0.2794 -0.1778)
						)
						(arc
							(start -0.2794 0.1778)
							(mid -0.249642 0.249642)
							(end -0.1778 0.2794)
						)
						(arc
							(start 0.1778 0.2794)
							(mid 0.249642 0.249642)
							(end 0.2794 0.1778)
						)
						(arc
							(start 0.2794 -0.1778)
							(mid 0.249642 -0.249642)
							(end 0.1778 -0.2794)
						)
					)
					(width 0)
					(fill yes)
				)
			)
		)
		(pad "2" smd custom
			(at 0 0.4445 180)
			(size 0.1397 0.1397)
			(layers "F.Cu" "F.Mask" "F.Paste")
			(net "GND")
			(options
				(clearance outline)
				(anchor circle)
			)
			(primitives
				(gr_poly
					(pts
						(arc
							(start -0.1778 -0.2794)
							(mid -0.249642 -0.249642)
							(end -0.2794 -0.1778)
						)
						(arc
							(start -0.2794 0.1778)
							(mid -0.249642 0.249642)
							(end -0.1778 0.2794)
						)
						(arc
							(start 0.1778 0.2794)
							(mid 0.249642 0.249642)
							(end 0.2794 0.1778)
						)
						(arc
							(start 0.2794 -0.1778)
							(mid 0.249642 -0.249642)
							(end 0.1778 -0.2794)
						)
					)
					(width 0)
					(fill yes)
				)
			)
		)
	)
	(footprint ""
		(layer "F.Cu")
		(at 15.1257 -92.083382)
		(property "Reference" "D1404"
			(at 0 0 0)
			(layer "F.SilkS")
			(hide yes)
			(effects
				(font
					(size 1.27 1.27)
				)
			)
		)
		(property "Value" "BAT54WS-7-F-GP"
			(at 0 -6.7818 0)
			(unlocked yes)
			(layer "F.Fab")
			(hide yes)
			(effects
				(font
					(size 1.016 1.016)
					(thickness 0.1524)
				)
			)
		)
		(property "Device Type" "SOD323AKH42"
			(at 0 -8.6868 0)
			(unlocked yes)
			(layer "F.Fab")
			(hide yes)
			(effects
				(font
					(size 1.016 1.016)
					(thickness 0.1524)
				)
			)
		)
		(duplicate_pad_numbers_are_jumpers no)
		(fp_line
			(start -0.889 -1.9304)
			(end 0.889 -1.9304)
			(stroke
				(width 0.1524)
				(type default)
			)
			(layer "F.SilkS")
		)
		(fp_line
			(start -0.889 2.159)
			(end -0.889 -1.9304)
			(stroke
				(width 0.1524)
				(type default)
			)
			(layer "F.SilkS")
		)
		(fp_line
			(start 0.762 2.0574)
			(end -0.762 2.0574)
			(stroke
				(width 0.508)
				(type default)
			)
			(layer "F.SilkS")
		)
		(fp_line
			(start 0.889 -1.9304)
			(end 0.889 2.159)
			(stroke
				(width 0.1524)
				(type default)
			)
			(layer "F.SilkS")
		)
		(fp_line
			(start 0.889 2.159)
			(end -0.889 2.159)
			(stroke
				(width 0.1524)
				(type default)
			)
			(layer "F.SilkS")
		)
		(fp_rect
			(start -1.016 2.3114)
			(end 1.016 -2.0066)
			(stroke
				(width 0)
				(type default)
			)
			(fill no)
			(layer "F.CrtYd")
		)
		(fp_poly
			(pts
				(xy -1.016 -2.0066) (xy 1.016 -2.0066) (xy 1.016 2.3114) (xy -1.016 2.3114)
			)
			(stroke
				(width 0)
				(type default)
			)
			(fill no)
			(layer "F.Fab")
		)
		(pad "A" smd rect
			(at 0 -1.143)
			(size 0.5588 1.016)
			(layers "F.Cu" "F.Mask" "F.Paste")
			(net "BMC_SELF_HW_RST")
		)
		(pad "K" smd rect
			(at 0 1.143)
			(size 0.5588 1.016)
			(layers "F.Cu" "F.Mask" "F.Paste")
			(net "BMC_TPM_RST")
		)
	)
	(footprint ""
		(layer "F.Cu")
		(at 85.991954 -212.420454 180)
		(property "Reference" "C347"
			(at 0 0 180)
			(layer "F.SilkS")
			(hide yes)
			(effects
				(font
					(size 1.27 1.27)
				)
			)
		)
		(property "Value" "SCD22U10V2KX-1GP"
			(at 1.1811 -2.7051 180)
			(unlocked yes)
			(layer "F.Fab")
			(hide yes)
			(effects
				(font
					(size 1.016 1.016)
					(thickness 0.1524)
				)
			)
		)
		(property "Device Type" "C402H22"
			(at 1.1811 -4.2291 180)
			(unlocked yes)
			(layer "F.Fab")
			(hide yes)
			(effects
				(font
					(size 1.016 1.016)
					(thickness 0.1524)
				)
			)
		)
		(duplicate_pad_numbers_are_jumpers no)
		(fp_rect
			(start -0.4318 0.9525)
			(end 0.4318 -0.9525)
			(stroke
				(width 0)
				(type default)
			)
			(fill no)
			(layer "F.CrtYd")
		)
		(fp_rect
			(start -0.4318 0.9525)
			(end 0.4318 -0.9525)
			(stroke
				(width 0)
				(type default)
			)
			(fill no)
			(layer "F.Fab")
		)
		(pad "1" smd custom
			(at 0 -0.4445 180)
			(size 0.1524 0.1524)
			(layers "F.Cu" "F.Mask" "F.Paste")
			(net "PCIE_TX_CAP_P66")
			(options
				(clearance outline)
				(anchor circle)
			)
			(primitives
				(gr_poly
					(pts
						(arc
							(start 0.3048 -0.2032)
							(mid 0.275042 -0.275042)
							(end 0.2032 -0.3048)
						)
						(arc
							(start -0.2032 -0.3048)
							(mid -0.275042 -0.275042)
							(end -0.3048 -0.2032)
						)
						(arc
							(start -0.3048 0.2032)
							(mid -0.275042 0.275042)
							(end -0.2032 0.3048)
						)
						(arc
							(start 0.2032 0.3048)
							(mid 0.275042 0.275042)
							(end 0.3048 0.2032)
						)
					)
					(width 0)
					(fill yes)
				)
			)
		)
		(pad "2" smd custom
			(at 0 0.4445 180)
			(size 0.1524 0.1524)
			(layers "F.Cu" "F.Mask" "F.Paste")
			(net "PCIE_TX_P66")
			(options
				(clearance outline)
				(anchor circle)
			)
			(primitives
				(gr_poly
					(pts
						(arc
							(start 0.3048 -0.2032)
							(mid 0.275042 -0.275042)
							(end 0.2032 -0.3048)
						)
						(arc
							(start -0.2032 -0.3048)
							(mid -0.275042 -0.275042)
							(end -0.3048 -0.2032)
						)
						(arc
							(start -0.3048 0.2032)
							(mid -0.275042 0.275042)
							(end -0.2032 0.3048)
						)
						(arc
							(start 0.2032 0.3048)
							(mid 0.275042 0.275042)
							(end 0.3048 0.2032)
						)
					)
					(width 0)
					(fill yes)
				)
			)
		)
	)
	(footprint ""
		(layer "F.Cu")
		(at 36.847526 -162.66668 90)
		(property "Reference" "C239"
			(at 0 0 90)
			(layer "F.SilkS")
			(hide yes)
			(effects
				(font
					(size 1.27 1.27)
				)
			)
		)
		(property "Value" "SCD1U16V2KX-3GP"
			(at 1.1811 -2.7051 90)
			(unlocked yes)
			(layer "F.Fab")
			(hide yes)
			(effects
				(font
					(size 1.016 1.016)
					(thickness 0.1524)
				)
			)
		)
		(property "Device Type" "C402H22"
			(at 1.1811 -4.2291 90)
			(unlocked yes)
			(layer "F.Fab")
			(hide yes)
			(effects
				(font
					(size 1.016 1.016)
					(thickness 0.1524)
				)
			)
		)
		(duplicate_pad_numbers_are_jumpers no)
		(fp_rect
			(start -0.4318 0.9525)
			(end 0.4318 -0.9525)
			(stroke
				(width 0)
				(type default)
			)
			(fill no)
			(layer "F.CrtYd")
		)
		(fp_rect
			(start -0.4318 0.9525)
			(end 0.4318 -0.9525)
			(stroke
				(width 0)
				(type default)
			)
			(fill no)
			(layer "F.Fab")
		)
		(pad "1" smd custom
			(at 0 -0.4445 90)
			(size 0.1524 0.1524)
			(layers "F.Cu" "F.Mask" "F.Paste")
			(net "DDR_VREF")
			(options
				(clearance outline)
				(anchor circle)
			)
			(primitives
				(gr_poly
					(pts
						(arc
							(start 0.3048 -0.2032)
							(mid 0.275042 -0.275042)
							(end 0.2032 -0.3048)
						)
						(arc
							(start -0.2032 -0.3048)
							(mid -0.275042 -0.275042)
							(end -0.3048 -0.2032)
						)
						(arc
							(start -0.3048 0.2032)
							(mid -0.275042 0.275042)
							(end -0.2032 0.3048)
						)
						(arc
							(start 0.2032 0.3048)
							(mid 0.275042 0.275042)
							(end 0.3048 0.2032)
						)
					)
					(width 0)
					(fill yes)
				)
			)
		)
		(pad "2" smd custom
			(at 0 0.4445 90)
			(size 0.1524 0.1524)
			(layers "F.Cu" "F.Mask" "F.Paste")
			(net "GND")
			(options
				(clearance outline)
				(anchor circle)
			)
			(primitives
				(gr_poly
					(pts
						(arc
							(start 0.3048 -0.2032)
							(mid 0.275042 -0.275042)
							(end 0.2032 -0.3048)
						)
						(arc
							(start -0.2032 -0.3048)
							(mid -0.275042 -0.275042)
							(end -0.3048 -0.2032)
						)
						(arc
							(start -0.3048 0.2032)
							(mid -0.275042 0.275042)
							(end -0.2032 0.3048)
						)
						(arc
							(start 0.2032 0.3048)
							(mid 0.275042 0.275042)
							(end 0.3048 0.2032)
						)
					)
					(width 0)
					(fill yes)
				)
			)
		)
	)
)
